#ISCELL
  pure_quanta quanta_title_block_c *
  *
#ISCELL
  standard offpage *
  page164_i1
#ISCELL
  standard tap *
  page164_i10
#ISCELL
  standard tap *
  page164_i100
#ISCELL
  standard tap *
  page164_i101
#ISCELL
  standard tap *
  page164_i102
#ISCELL
  standard tap *
  page164_i103
#ISCELL
  standard tap *
  page164_i104
#ISCELL
  standard offpage *
  page164_i105
#ISCELL
  standard offpage *
  page164_i106
#ISCELL
  standard offpage *
  page164_i107
#ISCELL
  standard offpage *
  page164_i108
#ISCELL
  standard tap *
  page164_i109
#ISCELL
  standard tap *
  page164_i11
#ISCELL
  standard tap *
  page164_i110
#ISCELL
  standard tap *
  page164_i111
#ISCELL
  standard tap *
  page164_i112
#ISCELL
  standard tap *
  page164_i113
#ISCELL
  standard tap *
  page164_i114
#ISCELL
  standard tap *
  page164_i115
#ISCELL
  standard tap *
  page164_i116
#ISCELL
  standard tap *
  page164_i117
#ISCELL
  standard tap *
  page164_i118
#ISCELL
  standard tap *
  page164_i119
#ISCELL
  standard tap *
  page164_i12
#ISCELL
  standard tap *
  page164_i120
#CELL
  pure_quanta q_cap_diffbus *
  page164_i121
#CELL
  pure_quanta q_cap_diffbus *
  page164_i122
#CELL
  pure_quanta q_cap_diffbus *
  page164_i123
#CELL
  pure_quanta q_cap_diffbus *
  page164_i124
#CELL
  pure_quanta q_cap_diffbus *
  page164_i125
#CELL
  pure_quanta q_cap_diffbus *
  page164_i126
#CELL
  pure_quanta q_cap_diffbus *
  page164_i127
#CELL
  pure_quanta q_cap_diffbus *
  page164_i128
#ISCELL
  standard tap *
  page164_i129
#ISCELL
  standard tap *
  page164_i13
#ISCELL
  standard tap *
  page164_i130
#ISCELL
  standard tap *
  page164_i131
#ISCELL
  standard tap *
  page164_i132
#CELL
  pure_quanta q_cap_diffbus *
  page164_i133
#CELL
  pure_quanta q_cap_diffbus *
  page164_i134
#CELL
  pure_quanta q_cap_diffbus *
  page164_i135
#CELL
  pure_quanta q_cap_diffbus *
  page164_i136
#CELL
  pure_quanta q_cap_diffbus *
  page164_i137
#ISCELL
  standard tap *
  page164_i138
#ISCELL
  standard tap *
  page164_i139
#ISCELL
  standard tap *
  page164_i14
#ISCELL
  standard tap *
  page164_i140
#ISCELL
  standard tap *
  page164_i141
#ISCELL
  standard tap *
  page164_i142
#ISCELL
  standard tap *
  page164_i143
#ISCELL
  standard tap *
  page164_i144
#ISCELL
  standard tap *
  page164_i145
#ISCELL
  standard tap *
  page164_i146
#ISCELL
  standard tap *
  page164_i147
#ISCELL
  standard tap *
  page164_i148
#ISCELL
  standard tap *
  page164_i149
#ISCELL
  standard tap *
  page164_i15
#ISCELL
  standard tap *
  page164_i150
#CELL
  pure_quanta q_cap_diffbus *
  page164_i151
#CELL
  pure_quanta q_cap_diffbus *
  page164_i152
#CELL
  pure_quanta q_cap_diffbus *
  page164_i153
#CELL
  pure_quanta q_cap_diffbus *
  page164_i154
#CELL
  pure_quanta q_cap_diffbus *
  page164_i155
#CELL
  pure_quanta q_cap_diffbus *
  page164_i156
#CELL
  pure_quanta q_cap_diffbus *
  page164_i157
#CELL
  pure_quanta q_cap_diffbus *
  page164_i158
#CELL
  pure_quanta q_cap_diffbus *
  page164_i159
#ISCELL
  standard tap *
  page164_i16
#CELL
  pure_quanta q_cap_diffbus *
  page164_i160
#ISCELL
  standard tap *
  page164_i161
#ISCELL
  standard tap *
  page164_i162
#ISCELL
  standard tap *
  page164_i163
#CELL
  pure_quanta q_cap_diffbus *
  page164_i164
#CELL
  pure_quanta q_cap_diffbus *
  page164_i165
#CELL
  pure_quanta q_cap_diffbus *
  page164_i166
#CELL
  pure_quanta q_cap_diffbus *
  page164_i167
#CELL
  pure_quanta q_cap_diffbus *
  page164_i168
#CELL
  pure_quanta q_cap_diffbus *
  page164_i169
#ISCELL
  standard tap *
  page164_i17
#ISCELL
  standard tap *
  page164_i170
#ISCELL
  standard tap *
  page164_i171
#ISCELL
  standard tap *
  page164_i172
#ISCELL
  standard tap *
  page164_i173
#ISCELL
  standard tap *
  page164_i174
#ISCELL
  standard tap *
  page164_i175
#ISCELL
  standard tap *
  page164_i176
#ISCELL
  standard tap *
  page164_i177
#ISCELL
  standard tap *
  page164_i178
#ISCELL
  standard tap *
  page164_i179
#ISCELL
  standard tap *
  page164_i18
#ISCELL
  standard tap *
  page164_i180
#ISCELL
  standard tap *
  page164_i181
#ISCELL
  standard tap *
  page164_i182
#ISCELL
  standard tap *
  page164_i183
#ISCELL
  standard tap *
  page164_i184
#ISCELL
  standard offpage *
  page164_i185
#ISCELL
  standard offpage *
  page164_i186
#ISCELL
  standard tap *
  page164_i187
#ISCELL
  standard tap *
  page164_i188
#ISCELL
  standard tap *
  page164_i189
#ISCELL
  standard tap *
  page164_i19
#ISCELL
  standard tap *
  page164_i190
#ISCELL
  standard tap *
  page164_i191
#ISCELL
  standard tap *
  page164_i192
#ISCELL
  standard tap *
  page164_i193
#ISCELL
  standard tap *
  page164_i194
#ISCELL
  standard tap *
  page164_i195
#ISCELL
  standard tap *
  page164_i196
#ISCELL
  standard tap *
  page164_i197
#ISCELL
  standard tap *
  page164_i198
#ISCELL
  standard tap *
  page164_i199
#ISCELL
  standard offpage *
  page164_i2
#ISCELL
  standard tap *
  page164_i20
#ISCELL
  standard tap *
  page164_i200
#ISCELL
  standard tap *
  page164_i201
#ISCELL
  standard tap *
  page164_i202
#ISCELL
  standard offpage *
  page164_i203
#ISCELL
  standard offpage *
  page164_i204
#ISCELL
  standard tap *
  page164_i205
#CELL
  pure_quanta q_cap_diffbus *
  page164_i206
#CELL
  pure_quanta q_cap_diffbus *
  page164_i207
#CELL
  pure_quanta q_cap_diffbus *
  page164_i208
#CELL
  pure_quanta q_cap_diffbus *
  page164_i21
#CELL
  pure_quanta q_cap_diffbus *
  page164_i22
#CELL
  pure_quanta q_cap_diffbus *
  page164_i23
#CELL
  pure_quanta q_cap_diffbus *
  page164_i24
#CELL
  pure_quanta q_cap_diffbus *
  page164_i25
#CELL
  pure_quanta q_cap_diffbus *
  page164_i26
#CELL
  pure_quanta q_cap_diffbus *
  page164_i27
#CELL
  pure_quanta q_cap_diffbus *
  page164_i28
#CELL
  pure_quanta q_cap_diffbus *
  page164_i29
#ISCELL
  standard offpage *
  page164_i3
#CELL
  pure_quanta q_cap_diffbus *
  page164_i30
#CELL
  pure_quanta q_cap_diffbus *
  page164_i31
#CELL
  pure_quanta q_cap_diffbus *
  page164_i32
#CELL
  pure_quanta q_cap_diffbus *
  page164_i33
#CELL
  pure_quanta q_cap_diffbus *
  page164_i34
#CELL
  pure_quanta q_cap_diffbus *
  page164_i35
#CELL
  pure_quanta q_cap_diffbus *
  page164_i36
#ISCELL
  standard tap *
  page164_i37
#ISCELL
  standard tap *
  page164_i38
#ISCELL
  standard tap *
  page164_i39
#ISCELL
  standard offpage *
  page164_i4
#ISCELL
  standard tap *
  page164_i40
#ISCELL
  standard tap *
  page164_i41
#ISCELL
  standard tap *
  page164_i42
#ISCELL
  standard tap *
  page164_i43
#ISCELL
  standard tap *
  page164_i44
#ISCELL
  standard tap *
  page164_i45
#ISCELL
  standard tap *
  page164_i46
#ISCELL
  standard tap *
  page164_i47
#ISCELL
  standard tap *
  page164_i48
#ISCELL
  standard tap *
  page164_i49
#ISCELL
  standard tap *
  page164_i5
#ISCELL
  standard tap *
  page164_i50
#ISCELL
  standard tap *
  page164_i51
#ISCELL
  standard tap *
  page164_i52
#CELL
  pure_quanta q_cap_diffbus *
  page164_i53
#CELL
  pure_quanta q_cap_diffbus *
  page164_i54
#CELL
  pure_quanta q_cap_diffbus *
  page164_i55
#CELL
  pure_quanta q_cap_diffbus *
  page164_i56
#CELL
  pure_quanta q_cap_diffbus *
  page164_i57
#CELL
  pure_quanta q_cap_diffbus *
  page164_i58
#CELL
  pure_quanta q_cap_diffbus *
  page164_i59
#ISCELL
  standard tap *
  page164_i6
#CELL
  pure_quanta q_cap_diffbus *
  page164_i60
#CELL
  pure_quanta q_cap_diffbus *
  page164_i61
#CELL
  pure_quanta q_cap_diffbus *
  page164_i62
#CELL
  pure_quanta q_cap_diffbus *
  page164_i63
#CELL
  pure_quanta q_cap_diffbus *
  page164_i64
#CELL
  pure_quanta q_cap_diffbus *
  page164_i65
#CELL
  pure_quanta q_cap_diffbus *
  page164_i66
#CELL
  pure_quanta q_cap_diffbus *
  page164_i67
#CELL
  pure_quanta q_cap_diffbus *
  page164_i68
#ISCELL
  standard tap *
  page164_i69
#ISCELL
  standard tap *
  page164_i7
#ISCELL
  standard tap *
  page164_i70
#ISCELL
  standard tap *
  page164_i71
#ISCELL
  standard tap *
  page164_i72
#ISCELL
  standard tap *
  page164_i73
#ISCELL
  standard tap *
  page164_i74
#ISCELL
  standard tap *
  page164_i75
#ISCELL
  standard tap *
  page164_i76
#ISCELL
  standard tap *
  page164_i77
#ISCELL
  standard tap *
  page164_i78
#ISCELL
  standard tap *
  page164_i79
#ISCELL
  standard tap *
  page164_i8
#ISCELL
  standard tap *
  page164_i80
#ISCELL
  standard tap *
  page164_i81
#ISCELL
  standard tap *
  page164_i82
#ISCELL
  standard tap *
  page164_i83
#ISCELL
  standard tap *
  page164_i84
#ISCELL
  standard tap *
  page164_i85
#ISCELL
  standard tap *
  page164_i86
#ISCELL
  standard tap *
  page164_i87
#ISCELL
  standard tap *
  page164_i88
#ISCELL
  standard tap *
  page164_i89
#ISCELL
  standard tap *
  page164_i9
#ISCELL
  standard tap *
  page164_i90
#ISCELL
  standard tap *
  page164_i91
#ISCELL
  standard tap *
  page164_i92
#ISCELL
  standard offpage *
  page164_i93
#ISCELL
  standard offpage *
  page164_i94
#ISCELL
  standard offpage *
  page164_i95
#ISCELL
  standard offpage *
  page164_i96
#ISCELL
  standard tap *
  page164_i97
#ISCELL
  standard tap *
  page164_i98
#ISCELL
  standard tap *
  page164_i99
